(kicad_pcb
	(version 20241229)
	(generator "pcbnew")
	(generator_version "9.0")
	(general
		(thickness 1.6642)
		(legacy_teardrops no)
	)
	(paper "A3")
	(title_block
		(title "PolarFire SoM")
		(date "2025-07-22")
		(rev "1.1.4")
		(company "Antmicro Ltd")
		(comment 1 "www.antmicro.com")
		(comment 9 "footprints 221-224 of 470")
	)
	(layers
		(0 "F.Cu" mixed)
		(4 "In1.Cu" power)
		(6 "In2.Cu" signal)
		(8 "In3.Cu" power)
		(10 "In4.Cu" signal)
		(12 "In5.Cu" power)
		(14 "In6.Cu" power)
		(16 "In7.Cu" signal)
		(18 "In8.Cu" power)
		(20 "In9.Cu" signal)
		(22 "In10.Cu" power)
		(24 "In11.Cu" signal)
		(26 "In12.Cu" signal)
		(2 "B.Cu" mixed)
		(9 "F.Adhes" user "F.Adhesive")
		(11 "B.Adhes" user "B.Adhesive")
		(13 "F.Paste" user)
		(15 "B.Paste" user)
		(5 "F.SilkS" user "F.Silkscreen")
		(7 "B.SilkS" user "B.Silkscreen")
		(1 "F.Mask" user)
		(3 "B.Mask" user)
		(17 "Dwgs.User" user "User.Drawings")
		(19 "Cmts.User" user "User.Comments")
		(21 "Eco1.User" user "User.Eco1")
		(23 "Eco2.User" user "User.Eco2")
		(25 "Edge.Cuts" user)
		(27 "Margin" user)
		(31 "F.CrtYd" user "F.Courtyard")
		(29 "B.CrtYd" user "B.Courtyard")
		(35 "F.Fab" user)
		(33 "B.Fab" user)
	)
	(footprint "antmicro-footprints:C_0402_1005Metric"
		(layer "B.Cu")
		(at 184.85 133.366 90)
		(descr "Capacitor SMD 0402")
		(tags "capacitor SMD 0402")
		(property "Reference" "C124"
			(at -2.014 -0.37 270)
			(layer "B.SilkS")
			(effects
				(font
					(size 0.7 0.7)
					(thickness 0.15)
				)
				(justify right bottom mirror)
			)
		)
		(property "Value" "C_1u_0402"
			(at -1.022927 -2.155213 90)
			(layer "B.Fab")
			(hide yes)
			(effects
				(font
					(size 0.7 0.7)
					(thickness 0.15)
				)
				(justify right bottom mirror)
			)
		)
		(property "Datasheet" "https://product.tdk.com/en/search/capacitor/ceramic/mlcc/info?part_no=C1005X6S1A105K050BC"
			(at 0 0 90)
			(layer "F.Fab")
			(hide yes)
			(effects
				(font
					(size 1.27 1.27)
					(thickness 0.15)
				)
			)
		)
		(property "Description" "SMD Multilayer Ceramic Capacitor, 1 µF, 10 V, 0402 [1005 Metric], ± 10%, X6S, C"
			(at 0 0 90)
			(layer "F.Fab")
			(hide yes)
			(effects
				(font
					(size 1.27 1.27)
					(thickness 0.15)
				)
			)
		)
		(property "Author" "Antmicro"
			(at 318.216 -51.484 0)
			(layer "B.Fab")
			(hide yes)
			(effects
				(font
					(size 1 1)
					(thickness 0.15)
				)
				(justify mirror)
			)
		)
		(property "Dielectric" "X5R"
			(at 318.216 -51.484 0)
			(layer "B.Fab")
			(hide yes)
			(effects
				(font
					(size 1 1)
					(thickness 0.15)
				)
				(justify mirror)
			)
		)
		(property "License" "Apache-2.0"
			(at 318.216 -51.484 0)
			(layer "B.Fab")
			(hide yes)
			(effects
				(font
					(size 1 1)
					(thickness 0.15)
				)
				(justify mirror)
			)
		)
		(property "MPN" "C1005X6S1A105K050BC"
			(at 318.216 -51.484 0)
			(layer "B.Fab")
			(hide yes)
			(effects
				(font
					(size 1 1)
					(thickness 0.15)
				)
				(justify mirror)
			)
		)
		(property "Manufacturer" "TDK"
			(at 318.216 -51.484 0)
			(layer "B.Fab")
			(hide yes)
			(effects
				(font
					(size 1 1)
					(thickness 0.15)
				)
				(justify mirror)
			)
		)
		(property "Public" ""
			(at 318.216 -51.484 0)
			(layer "B.Fab")
			(hide yes)
			(effects
				(font
					(size 1 1)
					(thickness 0.15)
				)
				(justify mirror)
			)
		)
		(property "Val" "1u"
			(at 318.216 -51.484 0)
			(layer "B.Fab")
			(hide yes)
			(effects
				(font
					(size 1 1)
					(thickness 0.15)
				)
				(justify mirror)
			)
		)
		(property "Voltage" "16V"
			(at 318.216 -51.484 0)
			(layer "B.Fab")
			(hide yes)
			(effects
				(font
					(size 1 1)
					(thickness 0.15)
				)
				(justify mirror)
			)
		)
		(sheetname "/LPDDR4/")
		(sheetfile "lpddr.kicad_sch")
		(attr smd)
		(fp_rect
			(start -0.925 0.47)
			(end 0.925 -0.47)
			(stroke
				(width 0.05)
				(type default)
			)
			(fill no)
			(layer "B.CrtYd")
		)
		(fp_line
			(start 0.504 -0.248)
			(end -0.494 -0.248)
			(stroke
				(width 0.15)
				(type solid)
			)
			(layer "B.Fab")
		)
		(fp_line
			(start -0.494 -0.248)
			(end -0.494 0.25)
			(stroke
				(width 0.15)
				(type solid)
			)
			(layer "B.Fab")
		)
		(fp_line
			(start 0.504 0.25)
			(end 0.504 -0.248)
			(stroke
				(width 0.15)
				(type solid)
			)
			(layer "B.Fab")
		)
		(fp_line
			(start -0.494 0.25)
			(end 0.504 0.25)
			(stroke
				(width 0.15)
				(type solid)
			)
			(layer "B.Fab")
		)
		(fp_text user "${REFERENCE}"
			(at -0.939 -4.599 270)
			(layer "B.Fab")
			(effects
				(font
					(size 0.7 0.7)
					(thickness 0.15)
				)
				(justify left bottom mirror)
			)
		)
		(fp_text user "Author: Antmicro"
			(at -0.939 -3.399 270)
			(layer "B.Fab")
			(effects
				(font
					(size 0.7 0.7)
					(thickness 0.15)
				)
				(justify left bottom mirror)
			)
		)
		(fp_text user "License: Apache-2.0"
			(at -0.939 -5.799 270)
			(layer "B.Fab")
			(effects
				(font
					(size 0.7 0.7)
					(thickness 0.15)
				)
				(justify left bottom mirror)
			)
		)
		(pad "1" smd roundrect
			(at -0.48 0 90)
			(size 0.59 0.64)
			(layers "B.Cu" "B.Mask" "B.Paste")
			(roundrect_rratio 0.25)
			(net 417 "GND")
			(pintype "passive")
		)
		(pad "2" smd roundrect
			(at 0.48 0 90)
			(size 0.59 0.64)
			(layers "B.Cu" "B.Mask" "B.Paste")
			(roundrect_rratio 0.25)
			(net 48 "+1V8")
			(pintype "passive")
		)
	)
	(footprint "antmicro-footprints:C_0402_1005Metric"
		(layer "B.Cu")
		(at 194.7 140.564 90)
		(descr "Capacitor SMD 0402")
		(tags "capacitor SMD 0402")
		(property "Reference" "C31"
			(at 1.454 -1.56 270)
			(layer "B.SilkS")
			(effects
				(font
					(size 0.7 0.7)
					(thickness 0.15)
				)
				(justify left bottom mirror)
			)
		)
		(property "Value" "C_100n_0402"
			(at -1.022927 -2.155213 270)
			(layer "B.Fab")
			(hide yes)
			(effects
				(font
					(size 0.7 0.7)
					(thickness 0.15)
				)
				(justify left bottom mirror)
			)
		)
		(property "Datasheet" "https://www.murata.com/products/productdetail?partno=GRM155R61H104KE14%23"
			(at 0 0 90)
			(layer "F.Fab")
			(hide yes)
			(effects
				(font
					(size 1.27 1.27)
					(thickness 0.15)
				)
			)
		)
		(property "Description" "SMD Multilayer Ceramic Capacitor, 0.1 µF, 50 V, 0402 [1005 Metric], ± 10%, X5R, GRM Series"
			(at 0 0 90)
			(layer "F.Fab")
			(hide yes)
			(effects
				(font
					(size 1.27 1.27)
					(thickness 0.15)
				)
			)
		)
		(property "Author" "Antmicro"
			(at 335.264 -54.136 0)
			(layer "B.Fab")
			(hide yes)
			(effects
				(font
					(size 1 1)
					(thickness 0.15)
				)
				(justify mirror)
			)
		)
		(property "Dielectric" "X5R"
			(at 335.264 -54.136 0)
			(layer "B.Fab")
			(hide yes)
			(effects
				(font
					(size 1 1)
					(thickness 0.15)
				)
				(justify mirror)
			)
		)
		(property "License" "Apache-2.0"
			(at 335.264 -54.136 0)
			(layer "B.Fab")
			(hide yes)
			(effects
				(font
					(size 1 1)
					(thickness 0.15)
				)
				(justify mirror)
			)
		)
		(property "MPN" "GRM155R61H104KE14D"
			(at 335.264 -54.136 0)
			(layer "B.Fab")
			(hide yes)
			(effects
				(font
					(size 1 1)
					(thickness 0.15)
				)
				(justify mirror)
			)
		)
		(property "Manufacturer" "Murata"
			(at 335.264 -54.136 0)
			(layer "B.Fab")
			(hide yes)
			(effects
				(font
					(size 1 1)
					(thickness 0.15)
				)
				(justify mirror)
			)
		)
		(property "Public" ""
			(at 335.264 -54.136 0)
			(layer "B.Fab")
			(hide yes)
			(effects
				(font
					(size 1 1)
					(thickness 0.15)
				)
				(justify mirror)
			)
		)
		(property "Val" "100n"
			(at 335.264 -54.136 0)
			(layer "B.Fab")
			(hide yes)
			(effects
				(font
					(size 1 1)
					(thickness 0.15)
				)
				(justify mirror)
			)
		)
		(property "Voltage" "50V"
			(at 335.264 -54.136 0)
			(layer "B.Fab")
			(hide yes)
			(effects
				(font
					(size 1 1)
					(thickness 0.15)
				)
				(justify mirror)
			)
		)
		(sheetname "/FPGA Supply/")
		(sheetfile "fpga-supply.kicad_sch")
		(attr smd)
		(fp_rect
			(start -0.925 0.47)
			(end 0.925 -0.47)
			(stroke
				(width 0.05)
				(type default)
			)
			(fill no)
			(layer "B.CrtYd")
		)
		(fp_line
			(start 0.504 -0.248)
			(end -0.494 -0.248)
			(stroke
				(width 0.15)
				(type solid)
			)
			(layer "B.Fab")
		)
		(fp_line
			(start -0.494 -0.248)
			(end -0.494 0.25)
			(stroke
				(width 0.15)
				(type solid)
			)
			(layer "B.Fab")
		)
		(fp_line
			(start 0.504 0.25)
			(end 0.504 -0.248)
			(stroke
				(width 0.15)
				(type solid)
			)
			(layer "B.Fab")
		)
		(fp_line
			(start -0.494 0.25)
			(end 0.504 0.25)
			(stroke
				(width 0.15)
				(type solid)
			)
			(layer "B.Fab")
		)
		(fp_text user "Author: Antmicro"
			(at -0.939 -3.399 270)
			(layer "B.Fab")
			(effects
				(font
					(size 0.7 0.7)
					(thickness 0.15)
				)
				(justify left bottom mirror)
			)
		)
		(fp_text user "License: Apache-2.0"
			(at -0.939 -5.799 270)
			(layer "B.Fab")
			(effects
				(font
					(size 0.7 0.7)
					(thickness 0.15)
				)
				(justify left bottom mirror)
			)
		)
		(fp_text user "${REFERENCE}"
			(at -0.939 -4.599 270)
			(layer "B.Fab")
			(effects
				(font
					(size 0.7 0.7)
					(thickness 0.15)
				)
				(justify left bottom mirror)
			)
		)
		(pad "1" smd roundrect
			(at -0.48 0 90)
			(size 0.59 0.64)
			(layers "B.Cu" "B.Mask" "B.Paste")
			(roundrect_rratio 0.25)
			(net 417 "GND")
			(pintype "passive")
		)
		(pad "2" smd roundrect
			(at 0.48 0 90)
			(size 0.59 0.64)
			(layers "B.Cu" "B.Mask" "B.Paste")
			(roundrect_rratio 0.25)
			(net 47 "+1V05")
			(pintype "passive")
		)
	)
	(footprint "antmicro-footprints:D_0402_1005Metric"
		(layer "B.Cu")
		(at 185.75 118.95 -90)
		(property "Reference" "D1"
			(at -2.4 -0.375 90)
			(layer "B.SilkS")
			(effects
				(font
					(size 0.7 0.7)
					(thickness 0.15)
				)
				(justify left bottom mirror)
			)
		)
		(property "Value" "AXGD10402KR"
			(at -2.54 -2.54 90)
			(layer "B.Fab")
			(hide yes)
			(effects
				(font
					(size 0.7 0.7)
					(thickness 0.15)
				)
				(justify left bottom mirror)
			)
		)
		(property "Datasheet" "https://www.littelfuse.com/media?resourcetype=datasheets&itemid=020b2bf2-064c-4ff1-a898-b4ec805b2fea&filename=littelfuse-xtremeguard-axgd-datasheet"
			(at 0 0 270)
			(layer "F.Fab")
			(hide yes)
			(effects
				(font
					(size 1.27 1.27)
					(thickness 0.15)
				)
			)
		)
		(property "Description" "Bidirectional TVS, 30 kV,  0402, 24 V, 0.04 pF"
			(at 0 0 270)
			(layer "F.Fab")
			(hide yes)
			(effects
				(font
					(size 1.27 1.27)
					(thickness 0.15)
				)
			)
		)
		(property "Author" "Antmicro"
			(at 66.8 304.7 0)
			(layer "B.Fab")
			(hide yes)
			(effects
				(font
					(size 1 1)
					(thickness 0.15)
				)
				(justify mirror)
			)
		)
		(property "License" "Apache-2.0"
			(at 66.8 304.7 0)
			(layer "B.Fab")
			(hide yes)
			(effects
				(font
					(size 1 1)
					(thickness 0.15)
				)
				(justify mirror)
			)
		)
		(property "MPN" "AXGD10402KR"
			(at 66.8 304.7 0)
			(layer "B.Fab")
			(hide yes)
			(effects
				(font
					(size 1 1)
					(thickness 0.15)
				)
				(justify mirror)
			)
		)
		(property "Manufacturer" "Littelfuse"
			(at 66.8 304.7 0)
			(layer "B.Fab")
			(hide yes)
			(effects
				(font
					(size 1 1)
					(thickness 0.15)
				)
				(justify mirror)
			)
		)
		(property "Public" ""
			(at 66.8 304.7 0)
			(layer "B.Fab")
			(hide yes)
			(effects
				(font
					(size 1 1)
					(thickness 0.15)
				)
				(justify mirror)
			)
		)
		(sheetname "/Supply/")
		(sheetfile "supply.kicad_sch")
		(attr smd)
		(fp_line
			(start 0.1 0.255)
			(end -0.1 0.255)
			(stroke
				(width 0.15)
				(type solid)
			)
			(layer "B.SilkS")
		)
		(fp_line
			(start -0.875 0.25)
			(end -0.875 -0.25)
			(stroke
				(width 0.15)
				(type solid)
			)
			(layer "B.SilkS")
		)
		(fp_line
			(start -0.1 -0.255)
			(end 0.1 -0.255)
			(stroke
				(width 0.15)
				(type solid)
			)
			(layer "B.SilkS")
		)
		(fp_rect
			(start -0.925 0.47)
			(end 0.925 -0.47)
			(stroke
				(width 0.05)
				(type default)
			)
			(fill no)
			(layer "B.CrtYd")
		)
		(fp_line
			(start -0.51 0.255)
			(end 0.51 0.255)
			(stroke
				(width 0.15)
				(type solid)
			)
			(layer "B.Fab")
		)
		(fp_line
			(start 0.51 0.255)
			(end 0.51 -0.255)
			(stroke
				(width 0.15)
				(type solid)
			)
			(layer "B.Fab")
		)
		(fp_line
			(start -0.2 0.25)
			(end -0.5 -0.05)
			(stroke
				(width 0.15)
				(type solid)
			)
			(layer "B.Fab")
		)
		(fp_line
			(start -0.51 -0.255)
			(end -0.51 0.255)
			(stroke
				(width 0.15)
				(type solid)
			)
			(layer "B.Fab")
		)
		(fp_line
			(start 0.51 -0.255)
			(end -0.51 -0.255)
			(stroke
				(width 0.15)
				(type solid)
			)
			(layer "B.Fab")
		)
		(fp_text user "License: Apache-2.0"
			(at -2.54 -5.74 90)
			(layer "B.Fab")
			(effects
				(font
					(size 0.7 0.7)
					(thickness 0.15)
				)
				(justify left bottom mirror)
			)
		)
		(fp_text user "Author: Antmicro"
			(at -2.54 -6.94 90)
			(layer "B.Fab")
			(effects
				(font
					(size 0.7 0.7)
					(thickness 0.15)
				)
				(justify left bottom mirror)
			)
		)
		(fp_text user "${REFERENCE}"
			(at -2.54 -4.54 90)
			(layer "B.Fab")
			(effects
				(font
					(size 0.7 0.7)
					(thickness 0.15)
				)
				(justify left bottom mirror)
			)
		)
		(pad "1" smd roundrect
			(at -0.48 0 270)
			(size 0.59 0.64)
			(layers "B.Cu" "B.Mask" "B.Paste")
			(roundrect_rratio 0.25)
			(net 417 "GND")
			(pinfunction "C")
			(pintype "passive")
		)
		(pad "2" smd roundrect
			(at 0.48 0 270)
			(size 0.59 0.64)
			(layers "B.Cu" "B.Mask" "B.Paste")
			(roundrect_rratio 0.25)
			(net 212 "GLOBAL_EN")
			(pinfunction "A")
			(pintype "passive")
		)
	)
	(footprint "antmicro-footprints:R_0402_1005Metric"
		(layer "B.Cu")
		(at 218.41 117.55 90)
		(descr "Resistor SMD 0402")
		(tags "resistor SMD 0402")
		(property "Reference" "R137"
			(at -0.9 0.39 270)
			(layer "B.SilkS")
			(effects
				(font
					(size 0.7 0.7)
					(thickness 0.15)
				)
				(justify left bottom mirror)
			)
		)
		(property "Value" "R_1k5_0402"
			(at -1.011843 -1.772047 270)
			(layer "B.Fab")
			(hide yes)
			(effects
				(font
					(size 0.7 0.7)
					(thickness 0.15)
				)
				(justify left bottom mirror)
			)
		)
		(property "Datasheet" "https://www.bourns.com/docs/product-datasheets/cr.pdf"
			(at 0 0 90)
			(layer "F.Fab")
			(hide yes)
			(effects
				(font
					(size 1.27 1.27)
					(thickness 0.15)
				)
			)
		)
		(property "Description" "SMD Chip Resistor, 1.5 kohm, ± 1%, 62.5 mW, 0402 [1005 Metric], Thick Film, General Purpose"
			(at 0 0 90)
			(layer "F.Fab")
			(hide yes)
			(effects
				(font
					(size 1.27 1.27)
					(thickness 0.15)
				)
			)
		)
		(property "Author" "Antmicro"
			(at 335.96 -100.86 0)
			(layer "B.Fab")
			(hide yes)
			(effects
				(font
					(size 1 1)
					(thickness 0.15)
				)
				(justify mirror)
			)
		)
		(property "License" "Apache-2.0"
			(at 335.96 -100.86 0)
			(layer "B.Fab")
			(hide yes)
			(effects
				(font
					(size 1 1)
					(thickness 0.15)
				)
				(justify mirror)
			)
		)
		(property "MPN" "CR0402-FX-1501GLF"
			(at 335.96 -100.86 0)
			(layer "B.Fab")
			(hide yes)
			(effects
				(font
					(size 1 1)
					(thickness 0.15)
				)
				(justify mirror)
			)
		)
		(property "Manufacturer" "Bourns"
			(at 335.96 -100.86 0)
			(layer "B.Fab")
			(hide yes)
			(effects
				(font
					(size 1 1)
					(thickness 0.15)
				)
				(justify mirror)
			)
		)
		(property "Public" ""
			(at 335.96 -100.86 0)
			(layer "B.Fab")
			(hide yes)
			(effects
				(font
					(size 1 1)
					(thickness 0.15)
				)
				(justify mirror)
			)
		)
		(property "Tolerance" "1%"
			(at 335.96 -100.86 0)
			(layer "B.Fab")
			(hide yes)
			(effects
				(font
					(size 1 1)
					(thickness 0.15)
				)
				(justify mirror)
			)
		)
		(property "Val" "1k5"
			(at 335.96 -100.86 0)
			(layer "B.Fab")
			(hide yes)
			(effects
				(font
					(size 1 1)
					(thickness 0.15)
				)
				(justify mirror)
			)
		)
		(sheetname "/Ethernet/")
		(sheetfile "ethernet.kicad_sch")
		(attr smd)
		(fp_rect
			(start -0.925 0.47)
			(end 0.925 -0.47)
			(stroke
				(width 0.05)
				(type default)
			)
			(fill no)
			(layer "B.CrtYd")
		)
		(fp_rect
			(start -0.5 0.25)
			(end 0.5 -0.25)
			(stroke
				(width 0.15)
				(type solid)
			)
			(fill no)
			(layer "B.Fab")
		)
		(fp_text user "Author: Antmicro"
			(at -0.95 -4.169 270)
			(layer "B.Fab")
			(effects
				(font
					(size 0.7 0.7)
					(thickness 0.15)
				)
				(justify left bottom mirror)
			)
		)
		(fp_text user "License: Apache-2.0"
			(at -0.95 -5.169 270)
			(layer "B.Fab")
			(effects
				(font
					(size 0.7 0.7)
					(thickness 0.15)
				)
				(justify left bottom mirror)
			)
		)
		(fp_text user "${REFERENCE}"
			(at -0.95 -3.168 270)
			(layer "B.Fab")
			(effects
				(font
					(size 0.7 0.7)
					(thickness 0.15)
				)
				(justify left bottom mirror)
			)
		)
		(pad "1" smd roundrect
			(at -0.48 0 90)
			(size 0.59 0.64)
			(layers "B.Cu" "B.Mask" "B.Paste")
			(roundrect_rratio 0.25)
			(net 50 "+3V3")
			(pintype "passive")
		)
		(pad "2" smd roundrect
			(at 0.48 0 90)
			(size 0.59 0.64)
			(layers "B.Cu" "B.Mask" "B.Paste")
			(roundrect_rratio 0.25)
			(net 343 "/Ethernet/ETH.MDIO")
			(pintype "passive")
		)
	)
)
